#ISCELL
  mstr_misc dns *
  *
#ISCELL
  mstr_misc prelim *
  *
#ISCELL
  mstr_symbols cad_note *
  *
#ISCELL
  mstr_symbols intel_corp_bpage *
  *
#ISCELL
  mstr_symbols gnd *
  page222_i1
#CELL
  mstr_discrete res *
  page222_i10
#ISCELL
  mstr_symbols gnd *
  page222_i11
#CELL
  mstr_discrete cap *
  page222_i12
#CELL
  mstr_vreg mic5166 *
  page222_i13
#ISCELL
  mstr_symbols gnd *
  page222_i14
#CELL
  mstr_discrete cap *
  page222_i15
#ISCELL
  mstr_symbols gnd *
  page222_i16
#CELL
  mstr_discrete cap *
  page222_i17
#ISCELL
  mstr_symbols gnd *
  page222_i18
#ISCELL
  mstr_symbols gnd *
  page222_i19
#CELL
  mstr_discrete cap *
  page222_i2
#CELL
  mstr_discrete cap *
  page222_i20
#ISCELL
  mstr_symbols gnd *
  page222_i21
#CELL
  mstr_discrete cap *
  page222_i22
#CELL
  mstr_discrete res *
  page222_i23
#ISCELL
  mstr_symbols p3v3 *
  page222_i24
#ISCELL
  mstr_symbols pvtt_def *
  page222_i25
#CELL
  mstr_discrete cap *
  page222_i28
#ISCELL
  mstr_symbols gnd *
  page222_i29
#ISCELL
  mstr_standard offpage *
  page222_i3
#CELL
  mstr_misc shunt *
  page222_i30
#CELL
  mstr_discrete res *
  page222_i31
#ISCELL
  mstr_standard offpage *
  page222_i33
#ISCELL
  mstr_symbols pvtt_def *
  page222_i34
#ISCELL
  mstr_symbols gnd *
  page222_i35
#ISCELL
  mstr_symbols pvddq_def *
  page222_i37
#CELL
  mstr_discrete res *
  page222_i4
#CELL
  dev_discrete cap_a *
  page222_i41
#CELL
  mstr_discrete cap *
  page222_i44
#CELL
  mstr_discrete cap *
  page222_i45
#CELL
  mstr_discrete cap *
  page222_i46
#CELL
  mstr_discrete res *
  page222_i5
#CELL
  mstr_discrete res *
  page222_i6
#ISCELL
  mstr_symbols p3v3 *
  page222_i7
#ISCELL
  mstr_symbols gnd *
  page222_i8
#CELL
  mstr_discrete cap *
  page222_i9
